(kicad_pcb
	(version 20260206)
	(generator "pcbnew")
	(generator_version "10.0")
	(general
		(thickness 1.6)
		(legacy_teardrops no)
	)
	(paper "A4")
	(title_block
		(title "9052_F0T_PDB_Converter_Brick_F_V03_1208_1600_OCP.brd")
		(comment 1 "Grand Teton / footprints 463-468 of 578")
	)
	(layers
		(0 "F.Cu" signal "TOP")
		(4 "In1.Cu" signal "GND")
		(6 "In2.Cu" signal "IN1")
		(8 "In3.Cu" signal "GND1")
		(10 "In4.Cu" signal "VCC")
		(12 "In5.Cu" signal "VCC1")
		(14 "In6.Cu" signal "GND2")
		(16 "In7.Cu" signal "IN2")
		(18 "In8.Cu" signal "GND3")
		(2 "B.Cu" signal "BOTTOM")
		(9 "F.Adhes" user "F.Adhesive")
		(11 "B.Adhes" user "B.Adhesive")
		(13 "F.Paste" user "Package Geometry/Pastemask Top")
		(15 "B.Paste" user "Package Geometry/Pastemask Bottom")
		(5 "F.SilkS" user "Ref Des/Silkscreen Top")
		(7 "B.SilkS" user "Ref Des/Silkscreen Bottom")
		(1 "F.Mask" user "Board Geometry/Soldermask Top")
		(3 "B.Mask" user "Board Geometry/Soldermask Bottom")
		(17 "Dwgs.User" user "User.Drawings")
		(19 "Cmts.User" user "User.Comments")
		(21 "Eco1.User" user "User.Eco1")
		(23 "Eco2.User" user "User.Eco2")
		(25 "Edge.Cuts" user "Board Geometry/Outline")
		(27 "Margin" user)
		(31 "F.CrtYd" user "Package Geometry/Place Bound Top")
		(29 "B.CrtYd" user "Package Geometry/Place Bound Bottom")
		(35 "F.Fab" user "Ref Des/Assembly Top")
		(33 "B.Fab" user "Ref Des/Assembly Bottom")
	)
	(footprint ""
		(layer "B.Cu")
		(at 277.876 -89.916)
		(property "Reference" "PR6970"
			(at 0 0 0)
			(layer "B.SilkS")
			(hide yes)
			(effects
				(font
					(size 1.27 1.27)
				)
				(justify mirror)
			)
		)
		(property "Value" ""
			(at 0 0 0)
			(layer "B.Fab")
			(effects
				(font
					(size 1.27 1.27)
				)
				(justify mirror)
			)
		)
		(duplicate_pad_numbers_are_jumpers no)
		(fp_line
			(start -0.7874 -0.4064)
			(end -0.7874 0.4064)
			(stroke
				(width 0.1524)
				(type default)
			)
			(layer "B.SilkS")
		)
		(fp_line
			(start -0.7874 0.4064)
			(end 0.7874 0.4064)
			(stroke
				(width 0.1524)
				(type default)
			)
			(layer "B.SilkS")
		)
		(fp_line
			(start 0.7874 -0.4064)
			(end -0.7874 -0.4064)
			(stroke
				(width 0.1524)
				(type default)
			)
			(layer "B.SilkS")
		)
		(fp_line
			(start 0.7874 0.4064)
			(end 0.7874 -0.4064)
			(stroke
				(width 0.1524)
				(type default)
			)
			(layer "B.SilkS")
		)
		(fp_line
			(start -0.67945 -0.3048)
			(end -0.67945 0.3048)
			(stroke
				(width 0.1)
				(type default)
			)
			(layer "B.Fab")
		)
		(fp_line
			(start -0.67945 0.3048)
			(end -0.120396 0.3048)
			(stroke
				(width 0.1)
				(type default)
			)
			(layer "B.Fab")
		)
		(fp_line
			(start -0.12065 -0.3048)
			(end -0.67945 -0.3048)
			(stroke
				(width 0.1)
				(type default)
			)
			(layer "B.Fab")
		)
		(fp_line
			(start -0.12065 -0.2794)
			(end -0.12065 -0.3048)
			(stroke
				(width 0.1)
				(type default)
			)
			(layer "B.Fab")
		)
		(fp_line
			(start -0.120396 0.2794)
			(end 0.12065 0.2794)
			(stroke
				(width 0.1)
				(type default)
			)
			(layer "B.Fab")
		)
		(fp_line
			(start -0.120396 0.3048)
			(end -0.120396 0.2794)
			(stroke
				(width 0.1)
				(type default)
			)
			(layer "B.Fab")
		)
		(fp_line
			(start 0.12065 -0.305054)
			(end 0.12065 -0.2794)
			(stroke
				(width 0.1)
				(type default)
			)
			(layer "B.Fab")
		)
		(fp_line
			(start 0.12065 -0.2794)
			(end -0.12065 -0.2794)
			(stroke
				(width 0.1)
				(type default)
			)
			(layer "B.Fab")
		)
		(fp_line
			(start 0.12065 0.2794)
			(end 0.12065 0.3048)
			(stroke
				(width 0.1)
				(type default)
			)
			(layer "B.Fab")
		)
		(fp_line
			(start 0.12065 0.3048)
			(end 0.67945 0.3048)
			(stroke
				(width 0.1)
				(type default)
			)
			(layer "B.Fab")
		)
		(fp_line
			(start 0.67945 -0.305054)
			(end 0.12065 -0.305054)
			(stroke
				(width 0.1)
				(type default)
			)
			(layer "B.Fab")
		)
		(fp_line
			(start 0.67945 0.3048)
			(end 0.67945 -0.305054)
			(stroke
				(width 0.1)
				(type default)
			)
			(layer "B.Fab")
		)
		(pad "1" smd rect
			(at 0.40005 0)
			(size 0.4572 0.508)
			(layers "B.Cu" "B.Mask" "B.Paste")
			(net "P52V_HS1_GATE2_R1")
		)
		(pad "2" smd rect
			(at -0.40005 0)
			(size 0.4572 0.508)
			(layers "B.Cu" "B.Mask" "B.Paste")
			(net "P52V_HS1_4287_GATE2_R")
		)
	)
	(footprint ""
		(layer "B.Cu")
		(at 238.252 -91.313 -90)
		(property "Reference" "R4"
			(at 0 0 90)
			(layer "B.SilkS")
			(hide yes)
			(effects
				(font
					(size 1.27 1.27)
				)
				(justify mirror)
			)
		)
		(property "Value" ""
			(at 0 0 90)
			(layer "B.Fab")
			(effects
				(font
					(size 1.27 1.27)
				)
				(justify mirror)
			)
		)
		(duplicate_pad_numbers_are_jumpers no)
		(fp_line
			(start -0.7874 0.4064)
			(end 0.7874 0.4064)
			(stroke
				(width 0.1524)
				(type default)
			)
			(layer "B.SilkS")
		)
		(fp_line
			(start 0.7874 0.4064)
			(end 0.7874 -0.4064)
			(stroke
				(width 0.1524)
				(type default)
			)
			(layer "B.SilkS")
		)
		(fp_line
			(start -0.7874 -0.4064)
			(end -0.7874 0.4064)
			(stroke
				(width 0.1524)
				(type default)
			)
			(layer "B.SilkS")
		)
		(fp_line
			(start 0.7874 -0.4064)
			(end -0.7874 -0.4064)
			(stroke
				(width 0.1524)
				(type default)
			)
			(layer "B.SilkS")
		)
		(fp_line
			(start -0.67945 0.3048)
			(end -0.120396 0.3048)
			(stroke
				(width 0.1)
				(type default)
			)
			(layer "B.Fab")
		)
		(fp_line
			(start -0.120396 0.3048)
			(end -0.120396 0.2794)
			(stroke
				(width 0.1)
				(type default)
			)
			(layer "B.Fab")
		)
		(fp_line
			(start 0.12065 0.3048)
			(end 0.67945 0.3048)
			(stroke
				(width 0.1)
				(type default)
			)
			(layer "B.Fab")
		)
		(fp_line
			(start 0.67945 0.3048)
			(end 0.67945 -0.305054)
			(stroke
				(width 0.1)
				(type default)
			)
			(layer "B.Fab")
		)
		(fp_line
			(start -0.120396 0.2794)
			(end 0.12065 0.2794)
			(stroke
				(width 0.1)
				(type default)
			)
			(layer "B.Fab")
		)
		(fp_line
			(start 0.12065 0.2794)
			(end 0.12065 0.3048)
			(stroke
				(width 0.1)
				(type default)
			)
			(layer "B.Fab")
		)
		(fp_line
			(start -0.12065 -0.2794)
			(end -0.12065 -0.3048)
			(stroke
				(width 0.1)
				(type default)
			)
			(layer "B.Fab")
		)
		(fp_line
			(start 0.12065 -0.2794)
			(end -0.12065 -0.2794)
			(stroke
				(width 0.1)
				(type default)
			)
			(layer "B.Fab")
		)
		(fp_line
			(start -0.67945 -0.3048)
			(end -0.67945 0.3048)
			(stroke
				(width 0.1)
				(type default)
			)
			(layer "B.Fab")
		)
		(fp_line
			(start -0.12065 -0.3048)
			(end -0.67945 -0.3048)
			(stroke
				(width 0.1)
				(type default)
			)
			(layer "B.Fab")
		)
		(fp_line
			(start 0.12065 -0.305054)
			(end 0.12065 -0.2794)
			(stroke
				(width 0.1)
				(type default)
			)
			(layer "B.Fab")
		)
		(fp_line
			(start 0.67945 -0.305054)
			(end 0.12065 -0.305054)
			(stroke
				(width 0.1)
				(type default)
			)
			(layer "B.Fab")
		)
		(pad "1" smd circle
			(at 0.40005 0 90)
			(size 0 0)
			(layers "B.Cu" "B.Mask" "B.Paste")
			(net "SMB_PDB_MISC_SCL_R")
		)
		(pad "2" smd circle
			(at -0.40005 0 90)
			(size 0 0)
			(layers "B.Cu" "B.Mask" "B.Paste")
			(net "SMB_PDB_MISC_SCL")
		)
	)
	(footprint ""
		(layer "B.Cu")
		(at 60.850018 -76.708 -90)
		(property "Reference" "PR325"
			(at 0 0 90)
			(layer "B.SilkS")
			(hide yes)
			(effects
				(font
					(size 1.27 1.27)
				)
				(justify mirror)
			)
		)
		(property "Value" ""
			(at 0 0 90)
			(layer "B.Fab")
			(effects
				(font
					(size 1.27 1.27)
				)
				(justify mirror)
			)
		)
		(duplicate_pad_numbers_are_jumpers no)
		(fp_line
			(start -0.7874 0.4064)
			(end 0.7874 0.4064)
			(stroke
				(width 0.1524)
				(type default)
			)
			(layer "B.SilkS")
		)
		(fp_line
			(start 0.7874 0.4064)
			(end 0.7874 -0.4064)
			(stroke
				(width 0.1524)
				(type default)
			)
			(layer "B.SilkS")
		)
		(fp_line
			(start -0.7874 -0.4064)
			(end -0.7874 0.4064)
			(stroke
				(width 0.1524)
				(type default)
			)
			(layer "B.SilkS")
		)
		(fp_line
			(start 0.7874 -0.4064)
			(end -0.7874 -0.4064)
			(stroke
				(width 0.1524)
				(type default)
			)
			(layer "B.SilkS")
		)
		(fp_line
			(start -0.67945 0.3048)
			(end -0.120396 0.3048)
			(stroke
				(width 0.1)
				(type default)
			)
			(layer "B.Fab")
		)
		(fp_line
			(start -0.120396 0.3048)
			(end -0.120396 0.2794)
			(stroke
				(width 0.1)
				(type default)
			)
			(layer "B.Fab")
		)
		(fp_line
			(start 0.12065 0.3048)
			(end 0.67945 0.3048)
			(stroke
				(width 0.1)
				(type default)
			)
			(layer "B.Fab")
		)
		(fp_line
			(start 0.67945 0.3048)
			(end 0.67945 -0.305054)
			(stroke
				(width 0.1)
				(type default)
			)
			(layer "B.Fab")
		)
		(fp_line
			(start -0.120396 0.2794)
			(end 0.12065 0.2794)
			(stroke
				(width 0.1)
				(type default)
			)
			(layer "B.Fab")
		)
		(fp_line
			(start 0.12065 0.2794)
			(end 0.12065 0.3048)
			(stroke
				(width 0.1)
				(type default)
			)
			(layer "B.Fab")
		)
		(fp_line
			(start -0.12065 -0.2794)
			(end -0.12065 -0.3048)
			(stroke
				(width 0.1)
				(type default)
			)
			(layer "B.Fab")
		)
		(fp_line
			(start 0.12065 -0.2794)
			(end -0.12065 -0.2794)
			(stroke
				(width 0.1)
				(type default)
			)
			(layer "B.Fab")
		)
		(fp_line
			(start -0.67945 -0.3048)
			(end -0.67945 0.3048)
			(stroke
				(width 0.1)
				(type default)
			)
			(layer "B.Fab")
		)
		(fp_line
			(start -0.12065 -0.3048)
			(end -0.67945 -0.3048)
			(stroke
				(width 0.1)
				(type default)
			)
			(layer "B.Fab")
		)
		(fp_line
			(start 0.12065 -0.305054)
			(end 0.12065 -0.2794)
			(stroke
				(width 0.1)
				(type default)
			)
			(layer "B.Fab")
		)
		(fp_line
			(start 0.67945 -0.305054)
			(end 0.12065 -0.305054)
			(stroke
				(width 0.1)
				(type default)
			)
			(layer "B.Fab")
		)
		(pad "1" smd circle
			(at 0.40005 0 90)
			(size 0 0)
			(layers "B.Cu" "B.Mask" "B.Paste")
			(net "BRICK3_PMBADD")
		)
		(pad "2" smd circle
			(at -0.40005 0 90)
			(size 0 0)
			(layers "B.Cu" "B.Mask" "B.Paste")
			(net "GND")
		)
	)
	(footprint ""
		(layer "B.Cu")
		(at 266.192 -32.766 180)
		(property "Reference" "PR27"
			(at 0 0 0)
			(layer "B.SilkS")
			(hide yes)
			(effects
				(font
					(size 1.27 1.27)
				)
				(justify mirror)
			)
		)
		(property "Value" ""
			(at 0 0 0)
			(layer "B.Fab")
			(effects
				(font
					(size 1.27 1.27)
				)
				(justify mirror)
			)
		)
		(duplicate_pad_numbers_are_jumpers no)
		(fp_line
			(start 0.7874 0.4064)
			(end 0.7874 -0.4064)
			(stroke
				(width 0.1524)
				(type default)
			)
			(layer "B.SilkS")
		)
		(fp_line
			(start 0.7874 -0.4064)
			(end -0.7874 -0.4064)
			(stroke
				(width 0.1524)
				(type default)
			)
			(layer "B.SilkS")
		)
		(fp_line
			(start -0.7874 0.4064)
			(end 0.7874 0.4064)
			(stroke
				(width 0.1524)
				(type default)
			)
			(layer "B.SilkS")
		)
		(fp_line
			(start -0.7874 -0.4064)
			(end -0.7874 0.4064)
			(stroke
				(width 0.1524)
				(type default)
			)
			(layer "B.SilkS")
		)
		(fp_line
			(start 0.67945 0.3048)
			(end 0.67945 -0.305054)
			(stroke
				(width 0.1)
				(type default)
			)
			(layer "B.Fab")
		)
		(fp_line
			(start 0.67945 -0.305054)
			(end 0.12065 -0.305054)
			(stroke
				(width 0.1)
				(type default)
			)
			(layer "B.Fab")
		)
		(fp_line
			(start 0.12065 0.3048)
			(end 0.67945 0.3048)
			(stroke
				(width 0.1)
				(type default)
			)
			(layer "B.Fab")
		)
		(fp_line
			(start 0.12065 0.2794)
			(end 0.12065 0.3048)
			(stroke
				(width 0.1)
				(type default)
			)
			(layer "B.Fab")
		)
		(fp_line
			(start 0.12065 -0.2794)
			(end -0.12065 -0.2794)
			(stroke
				(width 0.1)
				(type default)
			)
			(layer "B.Fab")
		)
		(fp_line
			(start 0.12065 -0.305054)
			(end 0.12065 -0.2794)
			(stroke
				(width 0.1)
				(type default)
			)
			(layer "B.Fab")
		)
		(fp_line
			(start -0.120396 0.3048)
			(end -0.120396 0.2794)
			(stroke
				(width 0.1)
				(type default)
			)
			(layer "B.Fab")
		)
		(fp_line
			(start -0.120396 0.2794)
			(end 0.12065 0.2794)
			(stroke
				(width 0.1)
				(type default)
			)
			(layer "B.Fab")
		)
		(fp_line
			(start -0.12065 -0.2794)
			(end -0.12065 -0.3048)
			(stroke
				(width 0.1)
				(type default)
			)
			(layer "B.Fab")
		)
		(fp_line
			(start -0.12065 -0.3048)
			(end -0.67945 -0.3048)
			(stroke
				(width 0.1)
				(type default)
			)
			(layer "B.Fab")
		)
		(fp_line
			(start -0.67945 0.3048)
			(end -0.120396 0.3048)
			(stroke
				(width 0.1)
				(type default)
			)
			(layer "B.Fab")
		)
		(fp_line
			(start -0.67945 -0.3048)
			(end -0.67945 0.3048)
			(stroke
				(width 0.1)
				(type default)
			)
			(layer "B.Fab")
		)
		(pad "1" smd circle
			(at 0.40005 0)
			(size 0 0)
			(layers "B.Cu" "B.Mask" "B.Paste")
			(net "P52V_HS1_INTVCC")
		)
		(pad "2" smd circle
			(at -0.40005 0)
			(size 0 0)
			(layers "B.Cu" "B.Mask" "B.Paste")
			(net "P52V_HS1_SCK")
		)
	)
	(footprint ""
		(layer "B.Cu")
		(at 216.154 -67.183 90)
		(property "Reference" "R137"
			(at 0 0 90)
			(layer "B.SilkS")
			(hide yes)
			(effects
				(font
					(size 1.27 1.27)
				)
				(justify mirror)
			)
		)
		(property "Value" ""
			(at 0 0 90)
			(layer "B.Fab")
			(effects
				(font
					(size 1.27 1.27)
				)
				(justify mirror)
			)
		)
		(duplicate_pad_numbers_are_jumpers no)
		(fp_line
			(start 0.7874 -0.4064)
			(end -0.7874 -0.4064)
			(stroke
				(width 0.1524)
				(type default)
			)
			(layer "B.SilkS")
		)
		(fp_line
			(start -0.7874 -0.4064)
			(end -0.7874 0.4064)
			(stroke
				(width 0.1524)
				(type default)
			)
			(layer "B.SilkS")
		)
		(fp_line
			(start 0.7874 0.4064)
			(end 0.7874 -0.4064)
			(stroke
				(width 0.1524)
				(type default)
			)
			(layer "B.SilkS")
		)
		(fp_line
			(start -0.7874 0.4064)
			(end 0.7874 0.4064)
			(stroke
				(width 0.1524)
				(type default)
			)
			(layer "B.SilkS")
		)
		(fp_line
			(start 0.67945 -0.305054)
			(end 0.12065 -0.305054)
			(stroke
				(width 0.1)
				(type default)
			)
			(layer "B.Fab")
		)
		(fp_line
			(start 0.12065 -0.305054)
			(end 0.12065 -0.2794)
			(stroke
				(width 0.1)
				(type default)
			)
			(layer "B.Fab")
		)
		(fp_line
			(start -0.12065 -0.3048)
			(end -0.67945 -0.3048)
			(stroke
				(width 0.1)
				(type default)
			)
			(layer "B.Fab")
		)
		(fp_line
			(start -0.67945 -0.3048)
			(end -0.67945 0.3048)
			(stroke
				(width 0.1)
				(type default)
			)
			(layer "B.Fab")
		)
		(fp_line
			(start 0.12065 -0.2794)
			(end -0.12065 -0.2794)
			(stroke
				(width 0.1)
				(type default)
			)
			(layer "B.Fab")
		)
		(fp_line
			(start -0.12065 -0.2794)
			(end -0.12065 -0.3048)
			(stroke
				(width 0.1)
				(type default)
			)
			(layer "B.Fab")
		)
		(fp_line
			(start 0.12065 0.2794)
			(end 0.12065 0.3048)
			(stroke
				(width 0.1)
				(type default)
			)
			(layer "B.Fab")
		)
		(fp_line
			(start -0.120396 0.2794)
			(end 0.12065 0.2794)
			(stroke
				(width 0.1)
				(type default)
			)
			(layer "B.Fab")
		)
		(fp_line
			(start 0.67945 0.3048)
			(end 0.67945 -0.305054)
			(stroke
				(width 0.1)
				(type default)
			)
			(layer "B.Fab")
		)
		(fp_line
			(start 0.12065 0.3048)
			(end 0.67945 0.3048)
			(stroke
				(width 0.1)
				(type default)
			)
			(layer "B.Fab")
		)
		(fp_line
			(start -0.120396 0.3048)
			(end -0.120396 0.2794)
			(stroke
				(width 0.1)
				(type default)
			)
			(layer "B.Fab")
		)
		(fp_line
			(start -0.67945 0.3048)
			(end -0.120396 0.3048)
			(stroke
				(width 0.1)
				(type default)
			)
			(layer "B.Fab")
		)
		(pad "1" smd circle
			(at 0.40005 0 270)
			(size 0 0)
			(layers "B.Cu" "B.Mask" "B.Paste")
			(net "BOARD_ID_1")
		)
		(pad "2" smd circle
			(at -0.40005 0 270)
			(size 0 0)
			(layers "B.Cu" "B.Mask" "B.Paste")
			(net "GND")
		)
	)
	(footprint ""
		(layer "B.Cu")
		(at 98.806 -76.327 180)
		(property "Reference" "R171"
			(at 0 0 0)
			(layer "B.SilkS")
			(hide yes)
			(effects
				(font
					(size 1.27 1.27)
				)
				(justify mirror)
			)
		)
		(property "Value" ""
			(at 0 0 0)
			(layer "B.Fab")
			(effects
				(font
					(size 1.27 1.27)
				)
				(justify mirror)
			)
		)
		(duplicate_pad_numbers_are_jumpers no)
		(fp_line
			(start 0.7874 0.4064)
			(end 0.7874 -0.4064)
			(stroke
				(width 0.1524)
				(type default)
			)
			(layer "B.SilkS")
		)
		(fp_line
			(start 0.7874 -0.4064)
			(end -0.7874 -0.4064)
			(stroke
				(width 0.1524)
				(type default)
			)
			(layer "B.SilkS")
		)
		(fp_line
			(start -0.7874 0.4064)
			(end 0.7874 0.4064)
			(stroke
				(width 0.1524)
				(type default)
			)
			(layer "B.SilkS")
		)
		(fp_line
			(start -0.7874 -0.4064)
			(end -0.7874 0.4064)
			(stroke
				(width 0.1524)
				(type default)
			)
			(layer "B.SilkS")
		)
		(fp_line
			(start 0.67945 0.3048)
			(end 0.67945 -0.305054)
			(stroke
				(width 0.1)
				(type default)
			)
			(layer "B.Fab")
		)
		(fp_line
			(start 0.67945 -0.305054)
			(end 0.12065 -0.305054)
			(stroke
				(width 0.1)
				(type default)
			)
			(layer "B.Fab")
		)
		(fp_line
			(start 0.12065 0.3048)
			(end 0.67945 0.3048)
			(stroke
				(width 0.1)
				(type default)
			)
			(layer "B.Fab")
		)
		(fp_line
			(start 0.12065 0.2794)
			(end 0.12065 0.3048)
			(stroke
				(width 0.1)
				(type default)
			)
			(layer "B.Fab")
		)
		(fp_line
			(start 0.12065 -0.2794)
			(end -0.12065 -0.2794)
			(stroke
				(width 0.1)
				(type default)
			)
			(layer "B.Fab")
		)
		(fp_line
			(start 0.12065 -0.305054)
			(end 0.12065 -0.2794)
			(stroke
				(width 0.1)
				(type default)
			)
			(layer "B.Fab")
		)
		(fp_line
			(start -0.120396 0.3048)
			(end -0.120396 0.2794)
			(stroke
				(width 0.1)
				(type default)
			)
			(layer "B.Fab")
		)
		(fp_line
			(start -0.120396 0.2794)
			(end 0.12065 0.2794)
			(stroke
				(width 0.1)
				(type default)
			)
			(layer "B.Fab")
		)
		(fp_line
			(start -0.12065 -0.2794)
			(end -0.12065 -0.3048)
			(stroke
				(width 0.1)
				(type default)
			)
			(layer "B.Fab")
		)
		(fp_line
			(start -0.12065 -0.3048)
			(end -0.67945 -0.3048)
			(stroke
				(width 0.1)
				(type default)
			)
			(layer "B.Fab")
		)
		(fp_line
			(start -0.67945 0.3048)
			(end -0.120396 0.3048)
			(stroke
				(width 0.1)
				(type default)
			)
			(layer "B.Fab")
		)
		(fp_line
			(start -0.67945 -0.3048)
			(end -0.67945 0.3048)
			(stroke
				(width 0.1)
				(type default)
			)
			(layer "B.Fab")
		)
		(pad "1" smd circle
			(at 0.40005 0)
			(size 0 0)
			(layers "B.Cu" "B.Mask" "B.Paste")
			(net "SMB_P52V_VPDB_SDA")
		)
		(pad "2" smd circle
			(at -0.40005 0)
			(size 0 0)
			(layers "B.Cu" "B.Mask" "B.Paste")
			(net "SMB_BRICK1_SDA")
		)
	)
)
